(kicad_pcb
	(version 20260206)
	(generator "pcbnew")
	(generator_version "10.0")
	(general
		(thickness 1.6)
		(legacy_teardrops no)
	)
	(paper "A4")
	(title_block
		(title "01162023_DA0F0TEBIF0_F0T_Expander_BD_F_brd_V02_OCP.brd")
		(comment 1 "Grand Teton / footprint 4451 of 9728 (PEX3), pads 1883-1999 of 2397")
	)
	(layers
		(0 "F.Cu" signal "TOP")
		(4 "In1.Cu" signal "GND")
		(6 "In2.Cu" signal "VCC")
		(8 "In3.Cu" signal "VCC1")
		(10 "In4.Cu" signal "GND1")
		(12 "In5.Cu" signal "IN1")
		(14 "In6.Cu" signal "GND2")
		(16 "In7.Cu" signal "IN2")
		(18 "In8.Cu" signal "GND3")
		(20 "In9.Cu" signal "IN3")
		(22 "In10.Cu" signal "GND4")
		(24 "In11.Cu" signal "IN4")
		(26 "In12.Cu" signal "GND5")
		(28 "In13.Cu" signal "IN5")
		(30 "In14.Cu" signal "GND6")
		(32 "In15.Cu" signal "IN6")
		(34 "In16.Cu" signal "GND7")
		(2 "B.Cu" signal "BOTTOM")
		(9 "F.Adhes" user "F.Adhesive")
		(11 "B.Adhes" user "B.Adhesive")
		(13 "F.Paste" user "Package Geometry/Pastemask Top")
		(15 "B.Paste" user "Package Geometry/Pastemask Bottom")
		(5 "F.SilkS" user "Ref Des/Silkscreen Top")
		(7 "B.SilkS" user "Ref Des/Silkscreen Bottom")
		(1 "F.Mask" user "Board Geometry/Soldermask Top")
		(3 "B.Mask" user "Board Geometry/Soldermask Bottom")
		(17 "Dwgs.User" user "User.Drawings")
		(19 "Cmts.User" user "User.Comments")
		(21 "Eco1.User" user "User.Eco1")
		(23 "Eco2.User" user "User.Eco2")
		(25 "Edge.Cuts" user "Board Geometry/Outline")
		(27 "Margin" user)
		(31 "F.CrtYd" user "Package Geometry/Place Bound Top")
		(29 "B.CrtYd" user "Package Geometry/Place Bound Bottom")
		(35 "F.Fab" user "Ref Des/Assembly Top")
		(33 "B.Fab" user "Ref Des/Assembly Bottom")
	)
	(footprint ""
		(layer "F.Cu")
		(at 407.949908 -295.89984)
		(property "Reference" "PEX3"
			(at -3.358642 35.5727 0)
			(unlocked yes)
			(layer "F.SilkS")
			(effects
				(font
					(size 2.032 1.524)
					(thickness 0.1524)
				)
				(justify left)
			)
		)
		(property "Value" ""
			(at 0 0 0)
			(layer "F.Fab")
			(effects
				(font
					(size 1.27 1.27)
				)
			)
		)
		(duplicate_pad_numbers_are_jumpers no)
		(pad "K25" smd circle
			(at 0 -14.249908)
			(size 0.4572 0.4572)
			(layers "F.Cu" "F.Mask" "F.Paste")
			(net "GND")
		)
		(pad "K26" smd circle
			(at 0.94996 -14.249908)
			(size 0.4572 0.4572)
			(layers "F.Cu" "F.Mask" "F.Paste")
			(net "GND")
		)
		(pad "K27" smd circle
			(at 1.89992 -14.249908)
			(size 0.4572 0.4572)
			(layers "F.Cu" "F.Mask" "F.Paste")
			(net "GND")
		)
		(pad "K28" smd circle
			(at 2.84988 -14.249908)
			(size 0.4572 0.4572)
			(layers "F.Cu" "F.Mask" "F.Paste")
			(net "GND")
		)
		(pad "K29" smd circle
			(at 3.800094 -14.249908)
			(size 0.4572 0.4572)
			(layers "F.Cu" "F.Mask" "F.Paste")
			(net "GND")
		)
		(pad "K30" smd circle
			(at 4.750054 -14.249908)
			(size 0.4572 0.4572)
			(layers "F.Cu" "F.Mask" "F.Paste")
			(net "GND")
		)
		(pad "K31" smd circle
			(at 5.700014 -14.249908)
			(size 0.4572 0.4572)
			(layers "F.Cu" "F.Mask" "F.Paste")
			(net "GND")
		)
		(pad "K32" smd circle
			(at 6.649974 -14.249908)
			(size 0.4572 0.4572)
			(layers "F.Cu" "F.Mask" "F.Paste")
			(net "GND")
		)
		(pad "K33" smd circle
			(at 7.599934 -14.249908)
			(size 0.4572 0.4572)
			(layers "F.Cu" "F.Mask" "F.Paste")
			(net "GND")
		)
		(pad "K34" smd circle
			(at 8.549894 -14.249908)
			(size 0.4572 0.4572)
			(layers "F.Cu" "F.Mask" "F.Paste")
			(net "GND")
		)
		(pad "K35" smd circle
			(at 9.500108 -14.249908)
			(size 0.4572 0.4572)
			(layers "F.Cu" "F.Mask" "F.Paste")
			(net "GND")
		)
		(pad "K36" smd circle
			(at 10.450068 -14.249908)
			(size 0.4572 0.4572)
			(layers "F.Cu" "F.Mask" "F.Paste")
			(net "GND")
		)
		(pad "K37" smd circle
			(at 11.400028 -14.249908)
			(size 0.4572 0.4572)
			(layers "F.Cu" "F.Mask" "F.Paste")
			(net "GND")
		)
		(pad "K38" smd circle
			(at 12.349988 -14.249908)
			(size 0.4572 0.4572)
			(layers "F.Cu" "F.Mask" "F.Paste")
			(net "GND")
		)
		(pad "K39" smd circle
			(at 13.299948 -14.249908)
			(size 0.4572 0.4572)
			(layers "F.Cu" "F.Mask" "F.Paste")
			(net "GND")
		)
		(pad "K40" smd circle
			(at 14.249908 -14.249908)
			(size 0.4572 0.4572)
			(layers "F.Cu" "F.Mask" "F.Paste")
			(net "GND")
		)
		(pad "K41" smd circle
			(at 15.200122 -14.249908)
			(size 0.4572 0.4572)
			(layers "F.Cu" "F.Mask" "F.Paste")
			(net "GND")
		)
		(pad "K42" smd circle
			(at 16.150082 -14.249908)
			(size 0.4572 0.4572)
			(layers "F.Cu" "F.Mask" "F.Paste")
			(net "GND")
		)
		(pad "K43" smd circle
			(at 17.100042 -14.249908)
			(size 0.4572 0.4572)
			(layers "F.Cu" "F.Mask" "F.Paste")
			(net "GND")
		)
		(pad "K44" smd circle
			(at 18.050002 -14.249908)
			(size 0.4572 0.4572)
			(layers "F.Cu" "F.Mask" "F.Paste")
			(net "GND")
		)
		(pad "K45" smd circle
			(at 18.999962 -14.249908)
			(size 0.4572 0.4572)
			(layers "F.Cu" "F.Mask" "F.Paste")
			(net "GND")
		)
		(pad "K46" smd circle
			(at 19.949922 -14.249908)
			(size 0.4572 0.4572)
			(layers "F.Cu" "F.Mask" "F.Paste")
			(net "GND")
		)
		(pad "K47" smd circle
			(at 20.899882 -14.249908)
			(size 0.4572 0.4572)
			(layers "F.Cu" "F.Mask" "F.Paste")
			(net "GND")
		)
		(pad "K48" smd circle
			(at 21.850096 -14.249908)
			(size 0.4572 0.4572)
			(layers "F.Cu" "F.Mask" "F.Paste")
			(net "P5E_PEX3_STN4_RX_DP<70>")
		)
		(pad "K49" smd circle
			(at 22.800056 -14.249908)
			(size 0.4572 0.4572)
			(layers "F.Cu" "F.Mask" "F.Paste")
			(net "P5E_PEX3_STN4_RX_DN<70>")
		)
		(pad "L1" smd circle
			(at -22.800056 -13.299948)
			(size 0.4572 0.4572)
			(layers "F.Cu" "F.Mask" "F.Paste")
			(net "GND")
		)
		(pad "L2" smd circle
			(at -21.850096 -13.299948)
			(size 0.4572 0.4572)
			(layers "F.Cu" "F.Mask" "F.Paste")
			(net "GND")
		)
		(pad "L3" smd circle
			(at -20.899882 -13.299948)
			(size 0.4572 0.4572)
			(layers "F.Cu" "F.Mask" "F.Paste")
			(net "P5E_PEX3_STN7_RX_DN<120>")
		)
		(pad "L4" smd circle
			(at -19.949922 -13.299948)
			(size 0.4572 0.4572)
			(layers "F.Cu" "F.Mask" "F.Paste")
			(net "P5E_PEX3_STN7_RX_DP<120>")
		)
		(pad "L5" smd circle
			(at -18.999962 -13.299948)
			(size 0.4572 0.4572)
			(layers "F.Cu" "F.Mask" "F.Paste")
			(net "GND")
		)
		(pad "L6" smd circle
			(at -18.050002 -13.299948)
			(size 0.4572 0.4572)
			(layers "F.Cu" "F.Mask" "F.Paste")
			(net "P5E_PEX3_STN7_TX_DN<120>")
		)
		(pad "L7" smd circle
			(at -17.100042 -13.299948)
			(size 0.4572 0.4572)
			(layers "F.Cu" "F.Mask" "F.Paste")
			(net "P5E_PEX3_STN7_TX_DP<120>")
		)
		(pad "L8" smd circle
			(at -16.150082 -13.299948)
			(size 0.4572 0.4572)
			(layers "F.Cu" "F.Mask" "F.Paste")
			(net "GND")
		)
		(pad "L9" smd circle
			(at -15.200122 -13.299948)
			(size 0.4572 0.4572)
			(layers "F.Cu" "F.Mask" "F.Paste")
			(net "GND")
		)
		(pad "L10" smd circle
			(at -14.249908 -13.299948)
			(size 0.4572 0.4572)
			(layers "F.Cu" "F.Mask" "F.Paste")
			(net "GND")
		)
		(pad "L11" smd circle
			(at -13.299948 -13.299948)
			(size 0.4572 0.4572)
			(layers "F.Cu" "F.Mask" "F.Paste")
			(net "GND")
		)
		(pad "L12" smd circle
			(at -12.349988 -13.299948)
			(size 0.4572 0.4572)
			(layers "F.Cu" "F.Mask" "F.Paste")
			(net "PEX3_DBG_MODE0")
		)
		(pad "L13" smd circle
			(at -11.400028 -13.299948)
			(size 0.4572 0.4572)
			(layers "F.Cu" "F.Mask" "F.Paste")
			(net "PEX3_DBG_MODE1")
		)
		(pad "L14" smd circle
			(at -10.450068 -13.299948)
			(size 0.4572 0.4572)
			(layers "F.Cu" "F.Mask" "F.Paste")
			(net "GND")
		)
		(pad "L15" smd circle
			(at -9.500108 -13.299948)
			(size 0.4572 0.4572)
			(layers "F.Cu" "F.Mask" "F.Paste")
			(net "PU_PEX3_ATPG_MODE_L")
		)
		(pad "L16" smd circle
			(at -8.549894 -13.299948)
			(size 0.4572 0.4572)
			(layers "F.Cu" "F.Mask" "F.Paste")
			(net "PU_PEX3_PAD_TRI_L")
		)
		(pad "L17" smd circle
			(at -7.599934 -13.299948)
			(size 0.4572 0.4572)
			(layers "F.Cu" "F.Mask" "F.Paste")
			(net "TP_PEX3_TDI")
		)
		(pad "L18" smd circle
			(at -6.649974 -13.299948)
			(size 0.4572 0.4572)
			(layers "F.Cu" "F.Mask" "F.Paste")
			(net "PEX3_DBG_SEL0")
		)
		(pad "L19" smd circle
			(at -5.700014 -13.299948)
			(size 0.4572 0.4572)
			(layers "F.Cu" "F.Mask" "F.Paste")
			(net "TP_PEX3_TDO")
		)
		(pad "L20" smd circle
			(at -4.750054 -13.299948)
			(size 0.4572 0.4572)
			(layers "F.Cu" "F.Mask" "F.Paste")
			(net "PU_PEX3_TR_TCK")
		)
		(pad "L21" smd circle
			(at -3.800094 -13.299948)
			(size 0.4572 0.4572)
			(layers "F.Cu" "F.Mask" "F.Paste")
			(net "GND")
		)
		(pad "L22" smd circle
			(at -2.84988 -13.299948)
			(size 0.4572 0.4572)
			(layers "F.Cu" "F.Mask" "F.Paste")
			(net "Net_5469")
		)
		(pad "L23" smd circle
			(at -1.89992 -13.299948)
			(size 0.4572 0.4572)
			(layers "F.Cu" "F.Mask" "F.Paste")
			(net "Net_5473")
		)
		(pad "L24" smd circle
			(at -0.94996 -13.299948)
			(size 0.4572 0.4572)
			(layers "F.Cu" "F.Mask" "F.Paste")
			(net "Net_5468")
		)
		(pad "L25" smd circle
			(at 0 -13.299948)
			(size 0.4572 0.4572)
			(layers "F.Cu" "F.Mask" "F.Paste")
			(net "PEX3_SPARE5")
		)
		(pad "L26" smd circle
			(at 0.94996 -13.299948)
			(size 0.4572 0.4572)
			(layers "F.Cu" "F.Mask" "F.Paste")
			(net "PU_PEX3_SIO_BLINK")
		)
		(pad "L27" smd circle
			(at 1.89992 -13.299948)
			(size 0.4572 0.4572)
			(layers "F.Cu" "F.Mask" "F.Paste")
			(net "PEX3_SPARE2")
		)
		(pad "L28" smd circle
			(at 2.84988 -13.299948)
			(size 0.4572 0.4572)
			(layers "F.Cu" "F.Mask" "F.Paste")
			(net "PEX3_SPARE6")
		)
		(pad "L29" smd circle
			(at 3.800094 -13.299948)
			(size 0.4572 0.4572)
			(layers "F.Cu" "F.Mask" "F.Paste")
			(net "Net_5458")
		)
		(pad "L30" smd circle
			(at 4.750054 -13.299948)
			(size 0.4572 0.4572)
			(layers "F.Cu" "F.Mask" "F.Paste")
			(net "PEX3_SPARE1")
		)
		(pad "L31" smd circle
			(at 5.700014 -13.299948)
			(size 0.4572 0.4572)
			(layers "F.Cu" "F.Mask" "F.Paste")
			(net "Net_5462")
		)
		(pad "L32" smd circle
			(at 6.649974 -13.299948)
			(size 0.4572 0.4572)
			(layers "F.Cu" "F.Mask" "F.Paste")
			(net "PEX3_SPARE3")
		)
		(pad "L33" smd circle
			(at 7.599934 -13.299948)
			(size 0.4572 0.4572)
			(layers "F.Cu" "F.Mask" "F.Paste")
			(net "Net_5454")
		)
		(pad "L34" smd circle
			(at 8.549894 -13.299948)
			(size 0.4572 0.4572)
			(layers "F.Cu" "F.Mask" "F.Paste")
			(net "SMB_PEX3_SLAVE1_SCL")
		)
		(pad "L35" smd circle
			(at 9.500108 -13.299948)
			(size 0.4572 0.4572)
			(layers "F.Cu" "F.Mask" "F.Paste")
			(net "Net_5451")
		)
		(pad "L36" smd circle
			(at 10.450068 -13.299948)
			(size 0.4572 0.4572)
			(layers "F.Cu" "F.Mask" "F.Paste")
			(net "Net_5481")
		)
		(pad "L37" smd circle
			(at 11.400028 -13.299948)
			(size 0.4572 0.4572)
			(layers "F.Cu" "F.Mask" "F.Paste")
			(net "PEX3_EXT_GPIO_LATCH_N")
		)
		(pad "L38" smd circle
			(at 12.349988 -13.299948)
			(size 0.4572 0.4572)
			(layers "F.Cu" "F.Mask" "F.Paste")
			(net "Net_5478")
		)
		(pad "L39" smd circle
			(at 13.299948 -13.299948)
			(size 0.4572 0.4572)
			(layers "F.Cu" "F.Mask" "F.Paste")
			(net "SMB_PEX3_SLAVE_SDA")
		)
		(pad "L40" smd circle
			(at 14.249908 -13.299948)
			(size 0.4572 0.4572)
			(layers "F.Cu" "F.Mask" "F.Paste")
			(net "GND")
		)
		(pad "L41" smd circle
			(at 15.200122 -13.299948)
			(size 0.4572 0.4572)
			(layers "F.Cu" "F.Mask" "F.Paste")
			(net "GND")
		)
		(pad "L42" smd circle
			(at 16.150082 -13.299948)
			(size 0.4572 0.4572)
			(layers "F.Cu" "F.Mask" "F.Paste")
			(net "GND")
		)
		(pad "L43" smd circle
			(at 17.100042 -13.299948)
			(size 0.4572 0.4572)
			(layers "F.Cu" "F.Mask" "F.Paste")
			(net "P5E_PEX3_STN4_TX_DP<69>")
		)
		(pad "L44" smd circle
			(at 18.050002 -13.299948)
			(size 0.4572 0.4572)
			(layers "F.Cu" "F.Mask" "F.Paste")
			(net "P5E_PEX3_STN4_TX_DN<69>")
		)
		(pad "L45" smd circle
			(at 18.999962 -13.299948)
			(size 0.4572 0.4572)
			(layers "F.Cu" "F.Mask" "F.Paste")
			(net "GND")
		)
		(pad "L46" smd circle
			(at 19.949922 -13.299948)
			(size 0.4572 0.4572)
			(layers "F.Cu" "F.Mask" "F.Paste")
			(net "P5E_PEX3_STN4_RX_DP<69>")
		)
		(pad "L47" smd circle
			(at 20.899882 -13.299948)
			(size 0.4572 0.4572)
			(layers "F.Cu" "F.Mask" "F.Paste")
			(net "P5E_PEX3_STN4_RX_DN<69>")
		)
		(pad "L48" smd circle
			(at 21.850096 -13.299948)
			(size 0.4572 0.4572)
			(layers "F.Cu" "F.Mask" "F.Paste")
			(net "GND")
		)
		(pad "L49" smd circle
			(at 22.800056 -13.299948)
			(size 0.4572 0.4572)
			(layers "F.Cu" "F.Mask" "F.Paste")
			(net "GND")
		)
		(pad "M1" smd circle
			(at -22.800056 -12.349988)
			(size 0.4572 0.4572)
			(layers "F.Cu" "F.Mask" "F.Paste")
			(net "P5E_PEX3_STN7_RX_DN<119>")
		)
		(pad "M2" smd circle
			(at -21.850096 -12.349988)
			(size 0.4572 0.4572)
			(layers "F.Cu" "F.Mask" "F.Paste")
			(net "P5E_PEX3_STN7_RX_DP<119>")
		)
		(pad "M3" smd circle
			(at -20.899882 -12.349988)
			(size 0.4572 0.4572)
			(layers "F.Cu" "F.Mask" "F.Paste")
			(net "GND")
		)
		(pad "M4" smd circle
			(at -19.949922 -12.349988)
			(size 0.4572 0.4572)
			(layers "F.Cu" "F.Mask" "F.Paste")
			(net "GND")
		)
		(pad "M5" smd circle
			(at -18.999962 -12.349988)
			(size 0.4572 0.4572)
			(layers "F.Cu" "F.Mask" "F.Paste")
			(net "GND")
		)
		(pad "M6" smd circle
			(at -18.050002 -12.349988)
			(size 0.4572 0.4572)
			(layers "F.Cu" "F.Mask" "F.Paste")
			(net "GND")
		)
		(pad "M7" smd circle
			(at -17.100042 -12.349988)
			(size 0.4572 0.4572)
			(layers "F.Cu" "F.Mask" "F.Paste")
			(net "GND")
		)
		(pad "M8" smd circle
			(at -16.150082 -12.349988)
			(size 0.4572 0.4572)
			(layers "F.Cu" "F.Mask" "F.Paste")
			(net "P5E_PEX3_STN7_TX_DN<119>")
		)
		(pad "M9" smd circle
			(at -15.200122 -12.349988)
			(size 0.4572 0.4572)
			(layers "F.Cu" "F.Mask" "F.Paste")
			(net "P5E_PEX3_STN7_TX_DP<119>")
		)
		(pad "M10" smd circle
			(at -14.249908 -12.349988)
			(size 0.4572 0.4572)
			(layers "F.Cu" "F.Mask" "F.Paste")
			(net "GND")
		)
		(pad "M11" smd circle
			(at -13.299948 -12.349988)
			(size 0.4572 0.4572)
			(layers "F.Cu" "F.Mask" "F.Paste")
			(net "GND")
		)
		(pad "M12" smd circle
			(at -12.349988 -12.349988)
			(size 0.4572 0.4572)
			(layers "F.Cu" "F.Mask" "F.Paste")
			(net "GND")
		)
		(pad "M13" smd circle
			(at -11.400028 -12.349988)
			(size 0.4572 0.4572)
			(layers "F.Cu" "F.Mask" "F.Paste")
			(net "IRQ_PEX3_CLKREQ_INT_N")
		)
		(pad "M14" smd circle
			(at -10.450068 -12.349988)
			(size 0.4572 0.4572)
			(layers "F.Cu" "F.Mask" "F.Paste")
			(net "GND")
		)
		(pad "M15" smd circle
			(at -9.500108 -12.349988)
			(size 0.4572 0.4572)
			(layers "F.Cu" "F.Mask" "F.Paste")
			(net "TP_PEX3_TCK")
		)
		(pad "M16" smd circle
			(at -8.549894 -12.349988)
			(size 0.4572 0.4572)
			(layers "F.Cu" "F.Mask" "F.Paste")
			(net "PEX3_DFT_IDDT")
		)
		(pad "M17" smd circle
			(at -7.599934 -12.349988)
			(size 0.4572 0.4572)
			(layers "F.Cu" "F.Mask" "F.Paste")
			(net "RST_PEX3_SYS_N")
		)
		(pad "M18" smd circle
			(at -6.649974 -12.349988)
			(size 0.4572 0.4572)
			(layers "F.Cu" "F.Mask" "F.Paste")
			(net "TP_PEX3_TRST_L")
		)
		(pad "M19" smd circle
			(at -5.700014 -12.349988)
			(size 0.4572 0.4572)
			(layers "F.Cu" "F.Mask" "F.Paste")
			(net "PEX3_DBG_SEL1")
		)
		(pad "M20" smd circle
			(at -4.750054 -12.349988)
			(size 0.4572 0.4572)
			(layers "F.Cu" "F.Mask" "F.Paste")
			(net "TP_PEX3_TMS")
		)
		(pad "M21" smd circle
			(at -3.800094 -12.349988)
			(size 0.4572 0.4572)
			(layers "F.Cu" "F.Mask" "F.Paste")
			(net "GND")
		)
		(pad "M22" smd circle
			(at -2.84988 -12.349988)
			(size 0.4572 0.4572)
			(layers "F.Cu" "F.Mask" "F.Paste")
			(net "Net_5471")
		)
		(pad "M23" smd circle
			(at -1.89992 -12.349988)
			(size 0.4572 0.4572)
			(layers "F.Cu" "F.Mask" "F.Paste")
			(net "Net_5472")
		)
		(pad "M24" smd circle
			(at -0.94996 -12.349988)
			(size 0.4572 0.4572)
			(layers "F.Cu" "F.Mask" "F.Paste")
			(net "Net_5474")
		)
		(pad "M25" smd circle
			(at 0 -12.349988)
			(size 0.4572 0.4572)
			(layers "F.Cu" "F.Mask" "F.Paste")
			(net "PEX3_SPARE4")
		)
		(pad "M26" smd circle
			(at 0.94996 -12.349988)
			(size 0.4572 0.4572)
			(layers "F.Cu" "F.Mask" "F.Paste")
			(net "PEX3_SPARE0")
		)
		(pad "M27" smd circle
			(at 1.89992 -12.349988)
			(size 0.4572 0.4572)
			(layers "F.Cu" "F.Mask" "F.Paste")
			(net "PEX3_SPARE7")
		)
		(pad "M28" smd circle
			(at 2.84988 -12.349988)
			(size 0.4572 0.4572)
			(layers "F.Cu" "F.Mask" "F.Paste")
			(net "I2C0_PEX3_SHPC_SDA")
		)
		(pad "M29" smd circle
			(at 3.800094 -12.349988)
			(size 0.4572 0.4572)
			(layers "F.Cu" "F.Mask" "F.Paste")
			(net "I2C0_PEX3_SHPC_SCL")
		)
		(pad "M30" smd circle
			(at 4.750054 -12.349988)
			(size 0.4572 0.4572)
			(layers "F.Cu" "F.Mask" "F.Paste")
			(net "Net_5452")
		)
		(pad "M31" smd circle
			(at 5.700014 -12.349988)
			(size 0.4572 0.4572)
			(layers "F.Cu" "F.Mask" "F.Paste")
			(net "Net_5453")
		)
		(pad "M32" smd circle
			(at 6.649974 -12.349988)
			(size 0.4572 0.4572)
			(layers "F.Cu" "F.Mask" "F.Paste")
			(net "Net_5463")
		)
		(pad "M33" smd circle
			(at 7.599934 -12.349988)
			(size 0.4572 0.4572)
			(layers "F.Cu" "F.Mask" "F.Paste")
			(net "Net_5457")
		)
		(pad "M34" smd circle
			(at 8.549894 -12.349988)
			(size 0.4572 0.4572)
			(layers "F.Cu" "F.Mask" "F.Paste")
			(net "Net_5461")
		)
		(pad "M35" smd circle
			(at 9.500108 -12.349988)
			(size 0.4572 0.4572)
			(layers "F.Cu" "F.Mask" "F.Paste")
			(net "I2C0_PEX3_SCL")
		)
		(pad "M36" smd circle
			(at 10.450068 -12.349988)
			(size 0.4572 0.4572)
			(layers "F.Cu" "F.Mask" "F.Paste")
			(net "Net_5480")
		)
		(pad "M37" smd circle
			(at 11.400028 -12.349988)
			(size 0.4572 0.4572)
			(layers "F.Cu" "F.Mask" "F.Paste")
			(net "Net_5479")
		)
		(pad "M38" smd circle
			(at 12.349988 -12.349988)
			(size 0.4572 0.4572)
			(layers "F.Cu" "F.Mask" "F.Paste")
			(net "SMB_PEX3_SLAVE1_SDA")
		)
		(pad "M39" smd circle
			(at 13.299948 -12.349988)
			(size 0.4572 0.4572)
			(layers "F.Cu" "F.Mask" "F.Paste")
			(net "I2C0_PEX3_SDA")
		)
		(pad "M40" smd circle
			(at 14.249908 -12.349988)
			(size 0.4572 0.4572)
			(layers "F.Cu" "F.Mask" "F.Paste")
			(net "GND")
		)
		(pad "M41" smd circle
			(at 15.200122 -12.349988)
			(size 0.4572 0.4572)
			(layers "F.Cu" "F.Mask" "F.Paste")
			(net "P5E_PEX3_STN4_TX_DP<68>")
		)
		(pad "M42" smd circle
			(at 16.150082 -12.349988)
			(size 0.4572 0.4572)
			(layers "F.Cu" "F.Mask" "F.Paste")
			(net "P5E_PEX3_STN4_TX_DN<68>")
		)
		(pad "M43" smd circle
			(at 17.100042 -12.349988)
			(size 0.4572 0.4572)
			(layers "F.Cu" "F.Mask" "F.Paste")
			(net "GND")
		)
	)
)
